(kicad_pcb
	(version 20260206)
	(generator "pcbnew")
	(generator_version "10.0")
	(general
		(thickness 1.6)
		(legacy_teardrops no)
	)
	(paper "A4")
	(title_block
		(title "9052_F0T_PDB_Converter_Brick_F_V03_1208_1600_OCP.brd")
		(comment 1 "Grand Teton / footprints 70-72 of 578")
	)
	(layers
		(0 "F.Cu" signal "TOP")
		(4 "In1.Cu" signal "GND")
		(6 "In2.Cu" signal "IN1")
		(8 "In3.Cu" signal "GND1")
		(10 "In4.Cu" signal "VCC")
		(12 "In5.Cu" signal "VCC1")
		(14 "In6.Cu" signal "GND2")
		(16 "In7.Cu" signal "IN2")
		(18 "In8.Cu" signal "GND3")
		(2 "B.Cu" signal "BOTTOM")
		(9 "F.Adhes" user "F.Adhesive")
		(11 "B.Adhes" user "B.Adhesive")
		(13 "F.Paste" user "Package Geometry/Pastemask Top")
		(15 "B.Paste" user "Package Geometry/Pastemask Bottom")
		(5 "F.SilkS" user "Ref Des/Silkscreen Top")
		(7 "B.SilkS" user "Ref Des/Silkscreen Bottom")
		(1 "F.Mask" user "Board Geometry/Soldermask Top")
		(3 "B.Mask" user "Board Geometry/Soldermask Bottom")
		(17 "Dwgs.User" user "User.Drawings")
		(19 "Cmts.User" user "User.Comments")
		(21 "Eco1.User" user "User.Eco1")
		(23 "Eco2.User" user "User.Eco2")
		(25 "Edge.Cuts" user "Board Geometry/Outline")
		(27 "Margin" user)
		(31 "F.CrtYd" user "Package Geometry/Place Bound Top")
		(29 "B.CrtYd" user "Package Geometry/Place Bound Bottom")
		(35 "F.Fab" user "Ref Des/Assembly Top")
		(33 "B.Fab" user "Ref Des/Assembly Bottom")
	)
	(footprint ""
		(layer "F.Cu")
		(at 211.455 -83.566 180)
		(property "Reference" "D1"
			(at 0.67564 -1.40335 0)
			(unlocked yes)
			(layer "F.SilkS")
			(effects
				(font
					(size 0.7874 0.5842)
					(thickness 0.1524)
				)
				(justify left)
			)
		)
		(property "Value" ""
			(at 0 0 180)
			(layer "F.Fab")
			(effects
				(font
					(size 1.27 1.27)
				)
			)
		)
		(duplicate_pad_numbers_are_jumpers no)
		(fp_line
			(start 1.16078 0.4826)
			(end -0.64008 0.4826)
			(stroke
				(width 0.1524)
				(type default)
			)
			(layer "F.SilkS")
		)
		(fp_line
			(start 1.16078 -0.4826)
			(end 1.16078 0.4826)
			(stroke
				(width 0.1524)
				(type default)
			)
			(layer "F.SilkS")
		)
		(fp_line
			(start 1.03378 0.4826)
			(end -0.79248 0.4826)
			(stroke
				(width 0.1524)
				(type default)
			)
			(layer "F.SilkS")
		)
		(fp_line
			(start 1.03378 -0.4826)
			(end 1.03378 0.4826)
			(stroke
				(width 0.1524)
				(type default)
			)
			(layer "F.SilkS")
		)
		(fp_line
			(start 0.90678 0.4826)
			(end -0.90678 0.4826)
			(stroke
				(width 0.1524)
				(type default)
			)
			(layer "F.SilkS")
		)
		(fp_line
			(start 0.90678 -0.4826)
			(end 0.90678 0.4826)
			(stroke
				(width 0.1524)
				(type default)
			)
			(layer "F.SilkS")
		)
		(fp_line
			(start -0.64008 -0.4826)
			(end 1.16078 -0.4826)
			(stroke
				(width 0.1524)
				(type default)
			)
			(layer "F.SilkS")
		)
		(fp_line
			(start -0.79248 -0.4826)
			(end 1.03378 -0.4826)
			(stroke
				(width 0.1524)
				(type default)
			)
			(layer "F.SilkS")
		)
		(fp_line
			(start -0.89408 -0.4826)
			(end 0.90678 -0.4826)
			(stroke
				(width 0.1524)
				(type default)
			)
			(layer "F.SilkS")
		)
		(fp_line
			(start -0.90678 0.4826)
			(end -0.90678 -0.4699)
			(stroke
				(width 0.1524)
				(type default)
			)
			(layer "F.SilkS")
		)
		(fp_line
			(start 0.499872 0.249936)
			(end -0.499872 0.249936)
			(stroke
				(width 0.1)
				(type default)
			)
			(layer "F.Fab")
		)
		(fp_line
			(start 0.499872 -0.249936)
			(end 0.499872 0.249936)
			(stroke
				(width 0.1)
				(type default)
			)
			(layer "F.Fab")
		)
		(fp_line
			(start -0.499872 0.249936)
			(end -0.499872 -0.249936)
			(stroke
				(width 0.1)
				(type default)
			)
			(layer "F.Fab")
		)
		(fp_line
			(start -0.499872 -0.249936)
			(end 0.499872 -0.249936)
			(stroke
				(width 0.1)
				(type default)
			)
			(layer "F.Fab")
		)
		(pad "A" smd rect
			(at -0.47498 0 180)
			(size 0.6096 0.7112)
			(layers "F.Cu" "F.Mask" "F.Paste")
			(net "LED_D1_R5")
		)
		(pad "C" smd rect
			(at 0.47498 0 180)
			(size 0.6096 0.7112)
			(layers "F.Cu" "F.Mask" "F.Paste")
			(net "GND")
		)
	)
	(footprint ""
		(layer "F.Cu")
		(at 79.121 -49.911)
		(property "Reference" "PC93"
			(at 0 0 0)
			(layer "F.SilkS")
			(hide yes)
			(effects
				(font
					(size 1.27 1.27)
				)
			)
		)
		(property "Value" ""
			(at 0 0 0)
			(layer "F.Fab")
			(effects
				(font
					(size 1.27 1.27)
				)
			)
		)
		(duplicate_pad_numbers_are_jumpers no)
		(fp_line
			(start -1.524 -0.762)
			(end 1.524 -0.762)
			(stroke
				(width 0.1524)
				(type default)
			)
			(layer "F.SilkS")
		)
		(fp_line
			(start -1.524 0.762)
			(end -1.524 -0.762)
			(stroke
				(width 0.1524)
				(type default)
			)
			(layer "F.SilkS")
		)
		(fp_line
			(start 1.524 -0.762)
			(end 1.524 0.762)
			(stroke
				(width 0.1524)
				(type default)
			)
			(layer "F.SilkS")
		)
		(fp_line
			(start 1.524 0.762)
			(end -1.524 0.762)
			(stroke
				(width 0.1524)
				(type default)
			)
			(layer "F.SilkS")
		)
		(fp_line
			(start -1.1049 -0.724916)
			(end -1.1049 0.724916)
			(stroke
				(width 0.1)
				(type default)
			)
			(layer "F.Fab")
		)
		(fp_line
			(start -1.1049 0.724916)
			(end 1.1049 0.724916)
			(stroke
				(width 0.1)
				(type default)
			)
			(layer "F.Fab")
		)
		(fp_line
			(start 1.1049 -0.724916)
			(end -1.1049 -0.724916)
			(stroke
				(width 0.1)
				(type default)
			)
			(layer "F.Fab")
		)
		(fp_line
			(start 1.1049 0.724916)
			(end 1.1049 -0.724916)
			(stroke
				(width 0.1)
				(type default)
			)
			(layer "F.Fab")
		)
		(pad "1" smd rect
			(at -0.889 0 180)
			(size 1.016 1.27)
			(layers "F.Cu" "F.Mask" "F.Paste")
			(net "P12V_BRICK")
		)
		(pad "2" smd rect
			(at 0.889 0 180)
			(size 1.016 1.27)
			(layers "F.Cu" "F.Mask" "F.Paste")
			(net "GND")
		)
	)
	(footprint ""
		(layer "F.Cu")
		(at 287.545272 -42.341546)
		(property "Reference" "PU7"
			(at -5.478272 -4.240784 0)
			(unlocked yes)
			(layer "F.SilkS")
			(effects
				(font
					(size 0.7874 0.5842)
					(thickness 0.1524)
				)
				(justify left)
			)
		)
		(property "Value" ""
			(at 0 0 0)
			(layer "F.Fab")
			(effects
				(font
					(size 1.27 1.27)
				)
			)
		)
		(duplicate_pad_numbers_are_jumpers no)
		(fp_line
			(start -4.05003 -3.549904)
			(end -4.05003 -3.0226)
			(stroke
				(width 0.1524)
				(type default)
			)
			(layer "F.SilkS")
		)
		(fp_line
			(start -4.05003 3.0226)
			(end -4.05003 3.549904)
			(stroke
				(width 0.1524)
				(type default)
			)
			(layer "F.SilkS")
		)
		(fp_line
			(start -4.05003 3.549904)
			(end -3.5052 3.549904)
			(stroke
				(width 0.1524)
				(type default)
			)
			(layer "F.SilkS")
		)
		(fp_line
			(start -3.5052 -3.549904)
			(end -4.05003 -3.549904)
			(stroke
				(width 0.1524)
				(type default)
			)
			(layer "F.SilkS")
		)
		(fp_line
			(start 0.0254 3.549904)
			(end 0.9906 3.549904)
			(stroke
				(width 0.1524)
				(type default)
			)
			(layer "F.SilkS")
		)
		(fp_line
			(start 0.9906 -3.549904)
			(end 0.0254 -3.549904)
			(stroke
				(width 0.1524)
				(type default)
			)
			(layer "F.SilkS")
		)
		(fp_line
			(start 3.5052 3.549904)
			(end 4.05003 3.549904)
			(stroke
				(width 0.1524)
				(type default)
			)
			(layer "F.SilkS")
		)
		(fp_line
			(start 4.05003 -3.549904)
			(end 3.5052 -3.549904)
			(stroke
				(width 0.1524)
				(type default)
			)
			(layer "F.SilkS")
		)
		(fp_line
			(start 4.05003 -3.0226)
			(end 4.05003 -3.549904)
			(stroke
				(width 0.1524)
				(type default)
			)
			(layer "F.SilkS")
		)
		(fp_line
			(start 4.05003 3.549904)
			(end 4.05003 3.0226)
			(stroke
				(width 0.1524)
				(type default)
			)
			(layer "F.SilkS")
		)
		(fp_poly
			(pts
				(xy -5.478272 -2.297684) (xy -5.478272 -3.203956) (xy -4.572 -2.75082)
			)
			(stroke
				(width 0)
				(type default)
			)
			(fill yes)
			(layer "F.SilkS")
		)
		(fp_line
			(start -4.05003 -3.549904)
			(end -4.05003 3.549904)
			(stroke
				(width 0.1)
				(type default)
			)
			(layer "F.Fab")
		)
		(fp_line
			(start -4.05003 3.549904)
			(end 4.05003 3.549904)
			(stroke
				(width 0.1)
				(type default)
			)
			(layer "F.Fab")
		)
		(fp_line
			(start 4.05003 -3.549904)
			(end -4.05003 -3.549904)
			(stroke
				(width 0.1)
				(type default)
			)
			(layer "F.Fab")
		)
		(fp_line
			(start 4.05003 3.549904)
			(end 4.05003 -3.549904)
			(stroke
				(width 0.1)
				(type default)
			)
			(layer "F.Fab")
		)
		(fp_poly
			(pts
				(xy -5.588 -3.25882) (xy -5.588 -2.24282) (xy -4.572 -2.75082)
			)
			(stroke
				(width 0)
				(type default)
			)
			(fill yes)
			(layer "F.Fab")
		)
		(pad "1" smd oval
			(at -3.9497 -2.75082 270)
			(size 0.3048 0.8382)
			(layers "F.Cu" "F.Mask" "F.Paste")
			(net "P52V_HS1_ISET")
		)
		(pad "2" smd oval
			(at -3.9497 -2.25044 270)
			(size 0.3048 0.8382)
			(layers "F.Cu" "F.Mask" "F.Paste")
			(net "P52V_HS1_ISTART")
		)
		(pad "3" smd oval
			(at -3.9497 -1.75006 270)
			(size 0.3048 0.8382)
			(layers "F.Cu" "F.Mask" "F.Paste")
			(net "P52V_HS1_VCAP")
		)
		(pad "4" smd oval
			(at -3.9497 -1.24968 270)
			(size 0.3048 0.8382)
			(layers "F.Cu" "F.Mask" "F.Paste")
			(net "P52V_HS1_ESTART_R")
		)
		(pad "5" smd oval
			(at -3.9497 -0.7493 270)
			(size 0.3048 0.8382)
			(layers "F.Cu" "F.Mask" "F.Paste")
			(net "P52V_HS1_EFAULT_R")
		)
		(pad "6" smd oval
			(at -3.9497 -0.24892 270)
			(size 0.3048 0.8382)
			(layers "F.Cu" "F.Mask" "F.Paste")
			(net "P52V_HS1_EN_BUF_DELAY")
		)
		(pad "7" smd oval
			(at -3.9497 0.24892 270)
			(size 0.3048 0.8382)
			(layers "F.Cu" "F.Mask" "F.Paste")
			(net "P52V_HS1_ADR0")
		)
		(pad "8" smd oval
			(at -3.9497 0.7493 270)
			(size 0.3048 0.8382)
			(layers "F.Cu" "F.Mask" "F.Paste")
			(net "P52V_HS1_ADR1")
		)
		(pad "9" smd oval
			(at -3.9497 1.24968 270)
			(size 0.3048 0.8382)
			(layers "F.Cu" "F.Mask" "F.Paste")
			(net "SMB_P52V_VPDB_SCL_R2")
		)
		(pad "10" smd oval
			(at -3.9497 1.75006 270)
			(size 0.3048 0.8382)
			(layers "F.Cu" "F.Mask" "F.Paste")
			(net "SMB_CM_HS1_3V3SB_DATI")
		)
		(pad "11" smd oval
			(at -3.9497 2.25044 270)
			(size 0.3048 0.8382)
			(layers "F.Cu" "F.Mask" "F.Paste")
			(net "SMB_CM_HS1_3V3SB_DATO")
		)
		(pad "12" smd oval
			(at -3.9497 2.75082 270)
			(size 0.3048 0.8382)
			(layers "F.Cu" "F.Mask" "F.Paste")
			(net "P52V_HS1_MCB")
		)
		(pad "13" smd oval
			(at -3.2512 3.44932)
			(size 0.3048 0.8382)
			(layers "F.Cu" "F.Mask" "F.Paste")
			(net "P52V_HS1_GPO2")
		)
		(pad "14" smd oval
			(at -2.75082 3.44932)
			(size 0.3048 0.8382)
			(layers "F.Cu" "F.Mask" "F.Paste")
			(net "P52V_HS1_GPO1")
		)
		(pad "15" smd oval
			(at -2.25044 3.44932)
			(size 0.3048 0.8382)
			(layers "F.Cu" "F.Mask" "F.Paste")
			(net "Net_298")
		)
		(pad "16" smd oval
			(at -1.75006 3.44932)
			(size 0.3048 0.8382)
			(layers "F.Cu" "F.Mask" "F.Paste")
			(net "Net_297")
		)
		(pad "17" smd oval
			(at -1.24968 3.44932)
			(size 0.3048 0.8382)
			(layers "F.Cu" "F.Mask" "F.Paste")
			(net "PWRGD_P52V_HS1_PG")
		)
		(pad "18" smd oval
			(at -0.7493 3.44932)
			(size 0.3048 0.8382)
			(layers "F.Cu" "F.Mask" "F.Paste")
			(net "P52V_HS1_PWRGIN")
		)
		(pad "19" smd oval
			(at -0.24892 3.44932)
			(size 0.3048 0.8382)
			(layers "F.Cu" "F.Mask" "F.Paste")
			(net "GND_FIELD_SIGNAL")
		)
		(pad "20" smd oval
			(at 1.24968 3.44932)
			(size 0.3048 0.8382)
			(layers "F.Cu" "F.Mask" "F.Paste")
			(net "P52V_HS1_VCC")
		)
		(pad "21" smd oval
			(at 1.75006 3.44932)
			(size 0.3048 0.8382)
			(layers "F.Cu" "F.Mask" "F.Paste")
			(net "P52V_HS1_VCC")
		)
		(pad "22" smd oval
			(at 2.25044 3.44932)
			(size 0.3048 0.8382)
			(layers "F.Cu" "F.Mask" "F.Paste")
			(net "P52V_HS1_VCC")
		)
		(pad "23" smd oval
			(at 2.75082 3.44932)
			(size 0.3048 0.8382)
			(layers "F.Cu" "F.Mask" "F.Paste")
			(net "P52V_HS1_VCC")
		)
		(pad "24" smd oval
			(at 3.2512 3.44932)
			(size 0.3048 0.8382)
			(layers "F.Cu" "F.Mask" "F.Paste")
			(net "P52V_HS1_VCC")
		)
		(pad "25" smd oval
			(at 3.9497 2.75082 270)
			(size 0.3048 0.8382)
			(layers "F.Cu" "F.Mask" "F.Paste")
			(net "Net_7")
		)
		(pad "26" smd oval
			(at 3.9497 2.25044 270)
			(size 0.3048 0.8382)
			(layers "F.Cu" "F.Mask" "F.Paste")
			(net "Net_11")
		)
		(pad "27" smd oval
			(at 3.9497 1.75006 270)
			(size 0.3048 0.8382)
			(layers "F.Cu" "F.Mask" "F.Paste")
			(net "Net_6")
		)
		(pad "28" smd oval
			(at 3.9497 1.24968 270)
			(size 0.3048 0.8382)
			(layers "F.Cu" "F.Mask" "F.Paste")
			(net "Net_5")
		)
		(pad "29" smd oval
			(at 3.9497 0.7493 270)
			(size 0.3048 0.8382)
			(layers "F.Cu" "F.Mask" "F.Paste")
			(net "P52V_HS1_VCP")
		)
		(pad "30" smd oval
			(at 3.9497 0.24892 270)
			(size 0.3048 0.8382)
			(layers "F.Cu" "F.Mask" "F.Paste")
			(net "P52V_HS1_DV_DT_R")
		)
		(pad "31" smd oval
			(at 3.9497 -0.24892 270)
			(size 0.3048 0.8382)
			(layers "F.Cu" "F.Mask" "F.Paste")
			(net "P52V_HS")
		)
		(pad "32" smd oval
			(at 3.9497 -0.7493 270)
			(size 0.3048 0.8382)
			(layers "F.Cu" "F.Mask" "F.Paste")
			(net "P52V_HS1_1272_GATE")
		)
		(pad "33" smd oval
			(at 3.9497 -1.24968 270)
			(size 0.3048 0.8382)
			(layers "F.Cu" "F.Mask" "F.Paste")
			(net "Net_9")
		)
		(pad "34" smd oval
			(at 3.9497 -1.75006 270)
			(size 0.3048 0.8382)
			(layers "F.Cu" "F.Mask" "F.Paste")
			(net "Net_4")
		)
		(pad "35" smd oval
			(at 3.9497 -2.25044 270)
			(size 0.3048 0.8382)
			(layers "F.Cu" "F.Mask" "F.Paste")
			(net "Net_3")
		)
		(pad "36" smd oval
			(at 3.9497 -2.75082 270)
			(size 0.3048 0.8382)
			(layers "F.Cu" "F.Mask" "F.Paste")
			(net "Net_12")
		)
		(pad "37" smd oval
			(at 3.2512 -3.44932)
			(size 0.3048 0.8382)
			(layers "F.Cu" "F.Mask" "F.Paste")
			(net "Net_10")
		)
		(pad "38" smd oval
			(at 2.75082 -3.44932)
			(size 0.3048 0.8382)
			(layers "F.Cu" "F.Mask" "F.Paste")
			(net "P52V_HS_1272_S_N")
		)
		(pad "39" smd oval
			(at 2.25044 -3.44932)
			(size 0.3048 0.8382)
			(layers "F.Cu" "F.Mask" "F.Paste")
			(net "P52V_HS_1272_S_P")
		)
		(pad "40" smd oval
			(at 1.75006 -3.44932)
			(size 0.3048 0.8382)
			(layers "F.Cu" "F.Mask" "F.Paste")
			(net "Net_8")
		)
		(pad "41" smd oval
			(at 1.24968 -3.44932)
			(size 0.3048 0.8382)
			(layers "F.Cu" "F.Mask" "F.Paste")
			(net "P52V_HS1_VCC")
		)
		(pad "42" smd oval
			(at -0.24892 -3.44932)
			(size 0.3048 0.8382)
			(layers "F.Cu" "F.Mask" "F.Paste")
			(net "P52V_HS1_VREG")
		)
		(pad "43" smd oval
			(at -0.7493 -3.44932)
			(size 0.3048 0.8382)
			(layers "F.Cu" "F.Mask" "F.Paste")
			(net "P52V_HS1_TEMPN")
		)
		(pad "44" smd oval
			(at -1.24968 -3.44932)
			(size 0.3048 0.8382)
			(layers "F.Cu" "F.Mask" "F.Paste")
			(net "P52V_HS1_TEMPP")
		)
		(pad "45" smd oval
			(at -1.75006 -3.44932)
			(size 0.3048 0.8382)
			(layers "F.Cu" "F.Mask" "F.Paste")
			(net "P52V_HS1_UVH")
		)
		(pad "46" smd oval
			(at -2.25044 -3.44932)
			(size 0.3048 0.8382)
			(layers "F.Cu" "F.Mask" "F.Paste")
			(net "P52V_HS1_UVLO_EN")
		)
		(pad "47" smd oval
			(at -2.75082 -3.44932)
			(size 0.3048 0.8382)
			(layers "F.Cu" "F.Mask" "F.Paste")
			(net "P52V_HS1_OV")
		)
		(pad "48" smd oval
			(at -3.2512 -3.44932)
			(size 0.3048 0.8382)
			(layers "F.Cu" "F.Mask" "F.Paste")
			(net "P52V_HS1_RND")
		)
		(pad "PAD1" smd rect
			(at -1.89738 0)
			(size 2.794 5.588)
			(layers "F.Cu" "F.Mask" "F.Paste")
			(net "GND_FIELD_SIGNAL")
		)
		(pad "PAD2" smd rect
			(at 1.55194 0)
			(size 1.4986 3.4036)
			(layers "F.Cu" "F.Mask" "F.Paste")
			(net "P52V_HS1_VCC")
		)
		(zone
			(layer "F.Cu")
			(hatch none 0.5)
			(connect_pads
				(clearance 0)
			)
			(min_thickness 0.25)
			(keepout
				(tracks not_allowed)
				(vias allowed)
				(pads allowed)
				(copperpour not_allowed)
				(footprints allowed)
			)
			(placement
				(enabled no)
				(sheetname "")
			)
			(fill
				(thermal_gap 0.5)
				(thermal_bridge_width 0.5)
				(island_removal_mode 0)
			)
			(polygon
				(pts
					(xy 291.025072 -45.313346) (xy 291.025072 -39.369746) (xy 288.307272 -39.369746) (xy 288.307272 -40.588946)
					(xy 289.907472 -40.588946) (xy 289.907472 -44.094146) (xy 288.307272 -44.094146) (xy 288.307272 -45.313346)
				)
			)
		)
		(zone
			(layer "F.Cu")
			(hatch none 0.5)
			(connect_pads
				(clearance 0)
			)
			(min_thickness 0.25)
			(keepout
				(tracks not_allowed)
				(vias allowed)
				(pads allowed)
				(copperpour not_allowed)
				(footprints allowed)
			)
			(placement
				(enabled no)
				(sheetname "")
			)
			(fill
				(thermal_gap 0.5)
				(thermal_bridge_width 0.5)
				(island_removal_mode 0)
			)
			(polygon
				(pts
					(xy 284.065472 -43.662346) (xy 284.065472 -39.369746) (xy 288.281872 -39.369746) (xy 288.281872 -45.313346)
					(xy 284.065472 -45.313346) (xy 284.065472 -43.687746) (xy 284.192472 -43.687746) (xy 284.192472 -45.186346)
					(xy 287.113472 -45.186346) (xy 287.113472 -39.496746) (xy 284.192472 -39.496746) (xy 284.192472 -43.662346)
				)
			)
		)
	)
)
